(kicad_pcb
	(version 20260206)
	(generator "pcbnew")
	(generator_version "10.0")
	(general
		(thickness 1.6)
		(legacy_teardrops no)
	)
	(paper "A4")
	(title_block
		(title "dpb — 14545-sa.0730WZS0815.brd")
		(comment 1 "Honey Badger (Wiwynn) / footprints 378-383 of 1066")
	)
	(layers
		(0 "F.Cu" signal "TOP")
		(4 "In1.Cu" signal "L2GND")
		(6 "In2.Cu" signal "L3")
		(8 "In3.Cu" signal "L4VCC")
		(10 "In4.Cu" signal "L5VCC")
		(12 "In5.Cu" signal "L6")
		(14 "In6.Cu" signal "L7GND")
		(2 "B.Cu" signal "BOTTOM")
		(9 "F.Adhes" user "F.Adhesive")
		(11 "B.Adhes" user "B.Adhesive")
		(13 "F.Paste" user "Package Geometry/Pastemask Top")
		(15 "B.Paste" user "Package Geometry/Pastemask Bottom")
		(5 "F.SilkS" user "Ref Des/Silkscreen Top")
		(7 "B.SilkS" user "Ref Des/Silkscreen Bottom")
		(1 "F.Mask" user "Board Geometry/Soldermask Top")
		(3 "B.Mask" user "Board Geometry/Soldermask Bottom")
		(17 "Dwgs.User" user "User.Drawings")
		(19 "Cmts.User" user "User.Comments")
		(21 "Eco1.User" user "User.Eco1")
		(23 "Eco2.User" user "User.Eco2")
		(25 "Edge.Cuts" user "Board Geometry/Outline")
		(27 "Margin" user)
		(31 "F.CrtYd" user "Package Geometry/Place Bound Top")
		(29 "B.CrtYd" user "Package Geometry/Place Bound Bottom")
		(35 "F.Fab" user "Ref Des/Assembly Top")
		(33 "B.Fab" user "Ref Des/Assembly Bottom")
	)
	(footprint ""
		(layer "F.Cu")
		(at 25.991312 -339.585808 90)
		(property "Reference" "C280"
			(at 0 0 90)
			(layer "F.SilkS")
			(hide yes)
			(effects
				(font
					(size 1.27 1.27)
				)
			)
		)
		(property "Value" "SCD01U50V2KX-1GP"
			(at 1.1811 -2.7051 90)
			(unlocked yes)
			(layer "F.Fab")
			(hide yes)
			(effects
				(font
					(size 1.016 1.016)
					(thickness 0.1524)
				)
			)
		)
		(property "Device Type" "C402H22"
			(at 1.1811 -4.2291 90)
			(unlocked yes)
			(layer "F.Fab")
			(hide yes)
			(effects
				(font
					(size 1.016 1.016)
					(thickness 0.1524)
				)
			)
		)
		(duplicate_pad_numbers_are_jumpers no)
		(fp_rect
			(start -0.4318 0.9525)
			(end 0.4318 -0.9525)
			(stroke
				(width 0)
				(type default)
			)
			(fill no)
			(layer "F.CrtYd")
		)
		(fp_rect
			(start -0.4318 0.9525)
			(end 0.4318 -0.9525)
			(stroke
				(width 0)
				(type default)
			)
			(fill no)
			(layer "F.Fab")
		)
		(pad "1" smd custom
			(at 0 -0.4445 90)
			(size 0.1524 0.1524)
			(layers "F.Cu" "F.Mask" "F.Paste")
			(net "SAS2X28_DRIVE_RX_N_B11")
			(options
				(clearance outline)
				(anchor circle)
			)
			(primitives
				(gr_poly
					(pts
						(arc
							(start 0.3048 -0.2032)
							(mid 0.275042 -0.275042)
							(end 0.2032 -0.3048)
						)
						(arc
							(start -0.2032 -0.3048)
							(mid -0.275042 -0.275042)
							(end -0.3048 -0.2032)
						)
						(arc
							(start -0.3048 0.2032)
							(mid -0.275042 0.275042)
							(end -0.2032 0.3048)
						)
						(arc
							(start 0.2032 0.3048)
							(mid 0.275042 0.275042)
							(end 0.3048 0.2032)
						)
					)
					(width 0)
					(fill yes)
				)
			)
		)
		(pad "2" smd custom
			(at 0 0.4445 90)
			(size 0.1524 0.1524)
			(layers "F.Cu" "F.Mask" "F.Paste")
			(net "SAS2X28_B_HDD11_RX_-")
			(options
				(clearance outline)
				(anchor circle)
			)
			(primitives
				(gr_poly
					(pts
						(arc
							(start 0.3048 -0.2032)
							(mid 0.275042 -0.275042)
							(end 0.2032 -0.3048)
						)
						(arc
							(start -0.2032 -0.3048)
							(mid -0.275042 -0.275042)
							(end -0.3048 -0.2032)
						)
						(arc
							(start -0.3048 0.2032)
							(mid -0.275042 0.275042)
							(end -0.2032 0.3048)
						)
						(arc
							(start 0.2032 0.3048)
							(mid 0.275042 0.275042)
							(end 0.3048 0.2032)
						)
					)
					(width 0)
					(fill yes)
				)
			)
		)
	)
	(footprint ""
		(layer "F.Cu")
		(at 216.584784 -172.436028)
		(property "Reference" "R152"
			(at 0 0 0)
			(layer "F.SilkS")
			(hide yes)
			(effects
				(font
					(size 1.27 1.27)
				)
			)
		)
		(property "Value" "220R3F-1-GP"
			(at -0.0254 -2.5146 0)
			(unlocked yes)
			(layer "F.Fab")
			(hide yes)
			(effects
				(font
					(size 1.016 1.016)
					(thickness 0.1524)
				)
			)
		)
		(property "Device Type" "R603H22"
			(at -0.0254 -4.0386 0)
			(unlocked yes)
			(layer "F.Fab")
			(hide yes)
			(effects
				(font
					(size 1.016 1.016)
					(thickness 0.1524)
				)
			)
		)
		(duplicate_pad_numbers_are_jumpers no)
		(fp_line
			(start -0.4826 0)
			(end -0.2032 0)
			(stroke
				(width 0.2032)
				(type default)
			)
			(layer "F.SilkS")
		)
		(fp_line
			(start 0.2032 0)
			(end 0.4826 0)
			(stroke
				(width 0.2032)
				(type default)
			)
			(layer "F.SilkS")
		)
		(fp_rect
			(start -0.5842 1.3335)
			(end 0.5842 -1.3335)
			(stroke
				(width 0)
				(type default)
			)
			(fill no)
			(layer "F.CrtYd")
		)
		(fp_rect
			(start -0.5842 1.3335)
			(end 0.5842 -1.3335)
			(stroke
				(width 0)
				(type default)
			)
			(fill no)
			(layer "F.Fab")
		)
		(pad "1" smd custom
			(at 0 -0.762)
			(size 0.2159 0.2159)
			(layers "F.Cu" "F.Mask" "F.Paste")
			(net "HDD_PRSNT_NET3")
			(options
				(clearance outline)
				(anchor circle)
			)
			(primitives
				(gr_poly
					(pts
						(arc
							(start -0.3302 -0.4318)
							(mid -0.402042 -0.402042)
							(end -0.4318 -0.3302)
						)
						(arc
							(start -0.4318 0.3302)
							(mid -0.402042 0.402042)
							(end -0.3302 0.4318)
						)
						(arc
							(start 0.3302 0.4318)
							(mid 0.402042 0.402042)
							(end 0.4318 0.3302)
						)
						(arc
							(start 0.4318 -0.3302)
							(mid 0.402042 -0.402042)
							(end 0.3302 -0.4318)
						)
					)
					(width 0)
					(fill yes)
				)
			)
		)
		(pad "2" smd custom
			(at 0 0.762)
			(size 0.2159 0.2159)
			(layers "F.Cu" "F.Mask" "F.Paste")
			(net "HDD_PRSNT3")
			(options
				(clearance outline)
				(anchor circle)
			)
			(primitives
				(gr_poly
					(pts
						(arc
							(start -0.3302 -0.4318)
							(mid -0.402042 -0.402042)
							(end -0.4318 -0.3302)
						)
						(arc
							(start -0.4318 0.3302)
							(mid -0.402042 0.402042)
							(end -0.3302 0.4318)
						)
						(arc
							(start 0.3302 0.4318)
							(mid 0.402042 0.402042)
							(end 0.4318 0.3302)
						)
						(arc
							(start 0.4318 -0.3302)
							(mid 0.402042 -0.402042)
							(end 0.3302 -0.4318)
						)
					)
					(width 0)
					(fill yes)
				)
			)
		)
	)
	(footprint ""
		(layer "F.Cu")
		(at 34.416746 -436.3847 180)
		(property "Reference" "U33"
			(at 0 0 180)
			(layer "F.SilkS")
			(hide yes)
			(effects
				(font
					(size 1.27 1.27)
				)
			)
		)
		(property "Value" "74LVC1G08GW-1-GP"
			(at -2.3368 -8.6868 180)
			(unlocked yes)
			(layer "F.Fab")
			(hide yes)
			(effects
				(font
					(size 1.016 1.016)
					(thickness 0.1524)
				)
			)
		)
		(property "Device Type" "SC70-5H44"
			(at -2.3114 -10.414 180)
			(unlocked yes)
			(layer "F.Fab")
			(hide yes)
			(effects
				(font
					(size 1.016 1.016)
					(thickness 0.1524)
				)
			)
		)
		(duplicate_pad_numbers_are_jumpers no)
		(fp_line
			(start 1.3843 -1.8034)
			(end 1.3843 -1.1176)
			(stroke
				(width 0.3302)
				(type default)
			)
			(layer "F.SilkS")
		)
		(fp_line
			(start 1.27 1.7018)
			(end -1.27 1.7018)
			(stroke
				(width 0.1524)
				(type default)
			)
			(layer "F.SilkS")
		)
		(fp_line
			(start 1.27 -1.7018)
			(end 1.27 1.7018)
			(stroke
				(width 0.1524)
				(type default)
			)
			(layer "F.SilkS")
		)
		(fp_line
			(start 0.6604 -1.8034)
			(end 1.3843 -1.8034)
			(stroke
				(width 0.3302)
				(type default)
			)
			(layer "F.SilkS")
		)
		(fp_line
			(start -1.27 1.7018)
			(end -1.27 -1.7018)
			(stroke
				(width 0.1524)
				(type default)
			)
			(layer "F.SilkS")
		)
		(fp_line
			(start -1.27 -1.7018)
			(end 1.27 -1.7018)
			(stroke
				(width 0.1524)
				(type default)
			)
			(layer "F.SilkS")
		)
		(fp_rect
			(start -1.524 1.9558)
			(end 1.524 -1.9558)
			(stroke
				(width 0)
				(type default)
			)
			(fill no)
			(layer "F.CrtYd")
		)
		(fp_poly
			(pts
				(xy -1.524 -1.9558) (xy 1.524 -1.9558) (xy 1.524 1.9558) (xy -1.524 1.9558)
			)
			(stroke
				(width 0)
				(type default)
			)
			(fill no)
			(layer "F.Fab")
		)
		(pad "1" smd rect
			(at 0.65024 -0.8255 180)
			(size 0.4064 1.2192)
			(layers "F.Cu" "F.Mask" "F.Paste")
			(net "SAS_EXP_B_PWR10")
		)
		(pad "2" smd rect
			(at 0 -0.8255 180)
			(size 0.4064 1.2192)
			(layers "F.Cu" "F.Mask" "F.Paste")
			(net "SAS_EXP_A_PWR10")
		)
		(pad "3" smd rect
			(at -0.65024 -0.8255 180)
			(size 0.4064 1.2192)
			(layers "F.Cu" "F.Mask" "F.Paste")
			(net "GND")
		)
		(pad "4" smd rect
			(at -0.65024 0.8255 180)
			(size 0.4064 1.2192)
			(layers "F.Cu" "F.Mask" "F.Paste")
			(net "DRIVE_PWR10")
		)
		(pad "5" smd rect
			(at 0.65024 0.8255 180)
			(size 0.4064 1.2192)
			(layers "F.Cu" "F.Mask" "F.Paste")
			(net "P3V3")
		)
	)
	(footprint ""
		(layer "F.Cu")
		(at 73.659746 -91.0717 90)
		(property "Reference" "U29"
			(at 0 0 90)
			(layer "F.SilkS")
			(hide yes)
			(effects
				(font
					(size 1.27 1.27)
				)
			)
		)
		(property "Value" "P2003EVG-GP"
			(at 0 -11.1252 90)
			(unlocked yes)
			(layer "F.Fab")
			(hide yes)
			(effects
				(font
					(size 1.016 1.016)
					(thickness 0.1524)
				)
			)
		)
		(property "Device Type" "SOIC8H79"
			(at 0 -12.6492 90)
			(unlocked yes)
			(layer "F.Fab")
			(hide yes)
			(effects
				(font
					(size 1.016 1.016)
					(thickness 0.1524)
				)
			)
		)
		(duplicate_pad_numbers_are_jumpers no)
		(fp_line
			(start 2.1336 -1.4224)
			(end -2.7432 -1.4224)
			(stroke
				(width 0.1524)
				(type default)
			)
			(layer "F.SilkS")
		)
		(fp_line
			(start -2.7432 -1.4224)
			(end -2.7432 1.4224)
			(stroke
				(width 0.1524)
				(type default)
			)
			(layer "F.SilkS")
		)
		(fp_line
			(start -2.7432 -0.508)
			(end -2.2352 0)
			(stroke
				(width 0.1524)
				(type default)
			)
			(layer "F.SilkS")
		)
		(fp_line
			(start -2.2352 0)
			(end -2.7432 0.508)
			(stroke
				(width 0.1524)
				(type default)
			)
			(layer "F.SilkS")
		)
		(fp_line
			(start 2.1336 1.4224)
			(end 2.1336 -1.4224)
			(stroke
				(width 0.1524)
				(type default)
			)
			(layer "F.SilkS")
		)
		(fp_line
			(start -2.7432 1.4224)
			(end 2.1336 1.4224)
			(stroke
				(width 0.1524)
				(type default)
			)
			(layer "F.SilkS")
		)
		(fp_line
			(start -2.6162 3.429)
			(end -2.6162 1.4732)
			(stroke
				(width 0.4064)
				(type default)
			)
			(layer "F.SilkS")
		)
		(fp_poly
			(pts
				(xy 2.2098 -1.4224) (xy 2.2098 1.4224) (xy -2.2225 1.4224) (xy -2.2225 -1.4224)
			)
			(stroke
				(width 0)
				(type default)
			)
			(fill yes)
			(layer "F.SilkS")
		)
		(fp_rect
			(start -2.4511 2.9972)
			(end 2.4511 -2.9972)
			(stroke
				(width 0)
				(type default)
			)
			(fill no)
			(layer "F.CrtYd")
		)
		(fp_poly
			(pts
				(xy -2.8194 3.6322) (xy -2.8194 -3.6322) (xy 2.8194 -3.6322) (xy 2.8194 -2.2987) (xy 2.4511 -2.2987)
				(xy 2.4511 -2.9972) (xy -2.4511 -2.9972) (xy -2.4511 2.9972) (xy 2.4511 2.9972) (xy 2.4511 -2.286)
				(xy 2.8194 -2.286) (xy 2.8194 3.6322)
			)
			(stroke
				(width 0)
				(type default)
			)
			(fill no)
			(layer "F.CrtYd")
		)
		(fp_rect
			(start -2.8194 3.6322)
			(end 2.8194 -3.6322)
			(stroke
				(width 0)
				(type default)
			)
			(fill no)
			(layer "F.Fab")
		)
		(pad "1" smd rect
			(at -1.905 2.54 90)
			(size 0.635 1.651)
			(layers "F.Cu" "F.Mask" "F.Paste")
			(net "P12V")
		)
		(pad "2" smd rect
			(at -0.635 2.54 90)
			(size 0.635 1.651)
			(layers "F.Cu" "F.Mask" "F.Paste")
			(net "P12V")
		)
		(pad "3" smd rect
			(at 0.635 2.54 90)
			(size 0.635 1.651)
			(layers "F.Cu" "F.Mask" "F.Paste")
			(net "P12V")
		)
		(pad "4" smd rect
			(at 1.905 2.54 90)
			(size 0.635 1.651)
			(layers "F.Cu" "F.Mask" "F.Paste")
			(net "SW_HDD9_N")
		)
		(pad "5" smd rect
			(at 1.905 -2.54 90)
			(size 0.635 1.651)
			(layers "F.Cu" "F.Mask" "F.Paste")
			(net "P12V_HDD9")
		)
		(pad "6" smd rect
			(at 0.635 -2.54 90)
			(size 0.635 1.651)
			(layers "F.Cu" "F.Mask" "F.Paste")
			(net "P12V_HDD9")
		)
		(pad "7" smd rect
			(at -0.635 -2.54 90)
			(size 0.635 1.651)
			(layers "F.Cu" "F.Mask" "F.Paste")
			(net "P12V_HDD9")
		)
		(pad "8" smd rect
			(at -1.905 -2.54 90)
			(size 0.635 1.651)
			(layers "F.Cu" "F.Mask" "F.Paste")
			(net "P12V_HDD9")
		)
	)
	(footprint ""
		(layer "F.Cu")
		(at 12.572746 -483.5017)
		(property "Reference" "PR51"
			(at 0 0 0)
			(layer "F.SilkS")
			(hide yes)
			(effects
				(font
					(size 1.27 1.27)
				)
			)
		)
		(property "Value" "10KR2F-2-GP"
			(at 0.064008 -3.993896 0)
			(unlocked yes)
			(layer "F.Fab")
			(hide yes)
			(effects
				(font
					(size 1.016 1.016)
					(thickness 0.1524)
				)
			)
		)
		(property "Device Type" "R402H16"
			(at 0.064008 -5.517896 0)
			(unlocked yes)
			(layer "F.Fab")
			(hide yes)
			(effects
				(font
					(size 1.016 1.016)
					(thickness 0.1524)
				)
			)
		)
		(duplicate_pad_numbers_are_jumpers no)
		(fp_line
			(start -0.508 -0.9398)
			(end -0.508 0.9398)
			(stroke
				(width 0.1524)
				(type default)
			)
			(layer "F.SilkS")
		)
		(fp_line
			(start 0.508 -0.9398)
			(end -0.508 -0.9398)
			(stroke
				(width 0.1524)
				(type default)
			)
			(layer "F.SilkS")
		)
		(fp_rect
			(start -0.508 0.9398)
			(end 0.508 -0.9398)
			(stroke
				(width 0)
				(type default)
			)
			(fill no)
			(layer "F.CrtYd")
		)
		(fp_rect
			(start -0.508 0.9398)
			(end 0.508 -0.9398)
			(stroke
				(width 0)
				(type default)
			)
			(fill no)
			(layer "F.Fab")
		)
		(pad "1" smd custom
			(at 0 -0.4445)
			(size 0.1397 0.1397)
			(layers "F.Cu" "F.Mask" "F.Paste")
			(net "P5VC_LL")
			(options
				(clearance outline)
				(anchor circle)
			)
			(primitives
				(gr_poly
					(pts
						(arc
							(start -0.1778 -0.2794)
							(mid -0.249642 -0.249642)
							(end -0.2794 -0.1778)
						)
						(arc
							(start -0.2794 0.1778)
							(mid -0.249642 0.249642)
							(end -0.1778 0.2794)
						)
						(arc
							(start 0.1778 0.2794)
							(mid 0.249642 0.249642)
							(end 0.2794 0.1778)
						)
						(arc
							(start 0.2794 -0.1778)
							(mid 0.249642 -0.249642)
							(end 0.1778 -0.2794)
						)
					)
					(width 0)
					(fill yes)
				)
			)
		)
		(pad "2" smd custom
			(at 0 0.4445)
			(size 0.1397 0.1397)
			(layers "F.Cu" "F.Mask" "F.Paste")
			(net "P5VC_LL_NET")
			(options
				(clearance outline)
				(anchor circle)
			)
			(primitives
				(gr_poly
					(pts
						(arc
							(start -0.1778 -0.2794)
							(mid -0.249642 -0.249642)
							(end -0.2794 -0.1778)
						)
						(arc
							(start -0.2794 0.1778)
							(mid -0.249642 0.249642)
							(end -0.1778 0.2794)
						)
						(arc
							(start 0.1778 0.2794)
							(mid 0.249642 0.249642)
							(end 0.2794 0.1778)
						)
						(arc
							(start 0.2794 -0.1778)
							(mid 0.249642 -0.249642)
							(end 0.1778 -0.2794)
						)
					)
					(width 0)
					(fill yes)
				)
			)
		)
	)
	(footprint ""
		(layer "F.Cu")
		(at 33.782 -305.308 90)
		(property "Reference" "R262"
			(at 0 0 90)
			(layer "F.SilkS")
			(hide yes)
			(effects
				(font
					(size 1.27 1.27)
				)
			)
		)
		(property "Value" "4K7R2J-2-GP"
			(at 0.064008 -3.993896 90)
			(unlocked yes)
			(layer "F.Fab")
			(hide yes)
			(effects
				(font
					(size 1.016 1.016)
					(thickness 0.1524)
				)
			)
		)
		(property "Device Type" "R402H16"
			(at 0.064008 -5.517896 90)
			(unlocked yes)
			(layer "F.Fab")
			(hide yes)
			(effects
				(font
					(size 1.016 1.016)
					(thickness 0.1524)
				)
			)
		)
		(duplicate_pad_numbers_are_jumpers no)
		(fp_line
			(start 0.508 -0.9398)
			(end -0.508 -0.9398)
			(stroke
				(width 0.1524)
				(type default)
			)
			(layer "F.SilkS")
		)
		(fp_line
			(start -0.508 -0.9398)
			(end -0.508 0.9398)
			(stroke
				(width 0.1524)
				(type default)
			)
			(layer "F.SilkS")
		)
		(fp_rect
			(start -0.508 0.9398)
			(end 0.508 -0.9398)
			(stroke
				(width 0)
				(type default)
			)
			(fill no)
			(layer "F.CrtYd")
		)
		(fp_rect
			(start -0.508 0.9398)
			(end 0.508 -0.9398)
			(stroke
				(width 0)
				(type default)
			)
			(fill no)
			(layer "F.Fab")
		)
		(pad "1" smd custom
			(at 0 -0.4445 90)
			(size 0.1397 0.1397)
			(layers "F.Cu" "F.Mask" "F.Paste")
			(net "P12V")
			(options
				(clearance outline)
				(anchor circle)
			)
			(primitives
				(gr_poly
					(pts
						(arc
							(start -0.1778 -0.2794)
							(mid -0.249642 -0.249642)
							(end -0.2794 -0.1778)
						)
						(arc
							(start -0.2794 0.1778)
							(mid -0.249642 0.249642)
							(end -0.1778 0.2794)
						)
						(arc
							(start 0.1778 0.2794)
							(mid 0.249642 0.249642)
							(end 0.2794 0.1778)
						)
						(arc
							(start 0.2794 -0.1778)
							(mid 0.249642 -0.249642)
							(end 0.1778 -0.2794)
						)
					)
					(width 0)
					(fill yes)
				)
			)
		)
		(pad "2" smd custom
			(at 0 0.4445 90)
			(size 0.1397 0.1397)
			(layers "F.Cu" "F.Mask" "F.Paste")
			(net "SW_HDD11_R")
			(options
				(clearance outline)
				(anchor circle)
			)
			(primitives
				(gr_poly
					(pts
						(arc
							(start -0.1778 -0.2794)
							(mid -0.249642 -0.249642)
							(end -0.2794 -0.1778)
						)
						(arc
							(start -0.2794 0.1778)
							(mid -0.249642 0.249642)
							(end -0.1778 0.2794)
						)
						(arc
							(start 0.1778 0.2794)
							(mid 0.249642 0.249642)
							(end 0.2794 0.1778)
						)
						(arc
							(start 0.2794 -0.1778)
							(mid 0.249642 -0.249642)
							(end 0.1778 -0.2794)
						)
					)
					(width 0)
					(fill yes)
				)
			)
		)
	)
)
